# T6G (Grand Teton) — schematic netlist excerpt (pin names and nets, part order shuffled) for the footprints in the layout excerpt that follows; sources: Cadence DE-HDL packaged netlist, KiCad conversion of 04192023_DAF0TMB3IC0_F0TG_MB_C_brd_V02_OCP.brd

R3860  Q_RES  0 5% EMPTY  pkg 0402LF  page 257 : A = P12V_OCP_V3_2_ISENSE_MPS_MAM ; B = P12V_OCP_V3_2_ISENSE_MAM

U38  SN74LVC1G11DCKR  IC  pkg SC70-6_0-65_2X1-25  page 259
  A  = PWRGD_P12V_MEM_CPU0_R
  GND  = GND
  B  = PWRGD_P12V_MEM_CPU1_R
  Y  = PWRGD_P12V_MEM
  VCC  = P1V8_AUX
  C  = PU_U38_6

(kicad_pcb
	(version 20260206)
	(generator "pcbnew")
	(generator_version "10.0")
	(general
		(thickness 1.6)
		(legacy_teardrops no)
	)
	(paper "A4")
	(title_block
		(title "04192023_DAF0TMB3IC0_F0TG_MB_C_brd_V02_OCP.brd")
		(comment 1 "Grand Teton / footprints 4507-4508 of 8354")
	)
	(layers
		(0 "F.Cu" signal "TOP")
		(4 "In1.Cu" signal "GND")
		(6 "In2.Cu" signal "IN1")
		(8 "In3.Cu" signal "GND1")
		(10 "In4.Cu" signal "IN2")
		(12 "In5.Cu" signal "GND2")
		(14 "In6.Cu" signal "IN3")
		(16 "In7.Cu" signal "GND3")
		(18 "In8.Cu" signal "VCC")
		(20 "In9.Cu" signal "VCC1")
		(22 "In10.Cu" signal "GND4")
		(24 "In11.Cu" signal "IN4")
		(26 "In12.Cu" signal "GND5")
		(28 "In13.Cu" signal "IN5")
		(30 "In14.Cu" signal "GND6")
		(32 "In15.Cu" signal "IN6")
		(34 "In16.Cu" signal "GND7")
		(2 "B.Cu" signal "BOTTOM")
		(9 "F.Adhes" user "F.Adhesive")
		(11 "B.Adhes" user "B.Adhesive")
		(13 "F.Paste" user "Package Geometry/Pastemask Top")
		(15 "B.Paste" user "Package Geometry/Pastemask Bottom")
		(5 "F.SilkS" user "Ref Des/Silkscreen Top")
		(7 "B.SilkS" user "Ref Des/Silkscreen Bottom")
		(1 "F.Mask" user "Board Geometry/Soldermask Top")
		(3 "B.Mask" user "Board Geometry/Soldermask Bottom")
		(17 "Dwgs.User" user "User.Drawings")
		(19 "Cmts.User" user "User.Comments")
		(21 "Eco1.User" user "User.Eco1")
		(23 "Eco2.User" user "User.Eco2")
		(25 "Edge.Cuts" user "Board Geometry/Outline")
		(27 "Margin" user)
		(31 "F.CrtYd" user "Package Geometry/Place Bound Top")
		(29 "B.CrtYd" user "Package Geometry/Place Bound Bottom")
		(35 "F.Fab" user "Ref Des/Assembly Top")
		(33 "B.Fab" user "Ref Des/Assembly Bottom")
	)
	(footprint ""
		(layer "F.Cu")
		(at 312.342022 -32.572706 180)
		(property "Reference" "R3860"
			(at 0 0 180)
			(layer "F.SilkS")
			(hide yes)
			(effects
				(font
					(size 1.27 1.27)
				)
			)
		)
		(property "Value" ""
			(at 0 0 180)
			(layer "F.Fab")
			(effects
				(font
					(size 1.27 1.27)
				)
			)
		)
		(duplicate_pad_numbers_are_jumpers no)
		(fp_line
			(start 0.7874 0.4064)
			(end -0.7874 0.4064)
			(stroke
				(width 0.1524)
				(type default)
			)
			(layer "F.SilkS")
		)
		(fp_line
			(start 0.7874 -0.4064)
			(end 0.7874 0.4064)
			(stroke
				(width 0.1524)
				(type default)
			)
			(layer "F.SilkS")
		)
		(fp_line
			(start -0.7874 0.4064)
			(end -0.7874 -0.4064)
			(stroke
				(width 0.1524)
				(type default)
			)
			(layer "F.SilkS")
		)
		(fp_line
			(start -0.7874 -0.4064)
			(end 0.7874 -0.4064)
			(stroke
				(width 0.1524)
				(type default)
			)
			(layer "F.SilkS")
		)
		(fp_line
			(start 0.67945 0.3048)
			(end 0.120396 0.3048)
			(stroke
				(width 0.1)
				(type default)
			)
			(layer "F.Fab")
		)
		(fp_line
			(start 0.67945 -0.3048)
			(end 0.67945 0.3048)
			(stroke
				(width 0.1)
				(type default)
			)
			(layer "F.Fab")
		)
		(fp_line
			(start 0.12065 -0.2794)
			(end 0.12065 -0.3048)
			(stroke
				(width 0.1)
				(type default)
			)
			(layer "F.Fab")
		)
		(fp_line
			(start 0.12065 -0.3048)
			(end 0.67945 -0.3048)
			(stroke
				(width 0.1)
				(type default)
			)
			(layer "F.Fab")
		)
		(fp_line
			(start 0.120396 0.3048)
			(end 0.120396 0.2794)
			(stroke
				(width 0.1)
				(type default)
			)
			(layer "F.Fab")
		)
		(fp_line
			(start 0.120396 0.2794)
			(end -0.12065 0.2794)
			(stroke
				(width 0.1)
				(type default)
			)
			(layer "F.Fab")
		)
		(fp_line
			(start -0.12065 0.3048)
			(end -0.67945 0.3048)
			(stroke
				(width 0.1)
				(type default)
			)
			(layer "F.Fab")
		)
		(fp_line
			(start -0.12065 0.2794)
			(end -0.12065 0.3048)
			(stroke
				(width 0.1)
				(type default)
			)
			(layer "F.Fab")
		)
		(fp_line
			(start -0.12065 -0.2794)
			(end 0.12065 -0.2794)
			(stroke
				(width 0.1)
				(type default)
			)
			(layer "F.Fab")
		)
		(fp_line
			(start -0.12065 -0.305054)
			(end -0.12065 -0.2794)
			(stroke
				(width 0.1)
				(type default)
			)
			(layer "F.Fab")
		)
		(fp_line
			(start -0.67945 0.3048)
			(end -0.67945 -0.305054)
			(stroke
				(width 0.1)
				(type default)
			)
			(layer "F.Fab")
		)
		(fp_line
			(start -0.67945 -0.305054)
			(end -0.12065 -0.305054)
			(stroke
				(width 0.1)
				(type default)
			)
			(layer "F.Fab")
		)
		(pad "1" smd rect
			(at -0.40005 0)
			(size 0.4572 0.508)
			(layers "F.Cu" "F.Mask" "F.Paste")
			(net "P12V_OCP_V3_2_ISENSE_MPS_MAM")
		)
		(pad "2" smd rect
			(at 0.40005 0)
			(size 0.4572 0.508)
			(layers "F.Cu" "F.Mask" "F.Paste")
			(net "P12V_OCP_V3_2_ISENSE_MAM")
		)
	)
	(footprint ""
		(layer "F.Cu")
		(at 98.344736 -123.628404 -90)
		(property "Reference" "U38"
			(at 0.808736 2.012188 90)
			(unlocked yes)
			(layer "F.SilkS")
			(effects
				(font
					(size 0.7874 0.5842)
					(thickness 0.1524)
				)
				(justify left)
			)
		)
		(property "Value" ""
			(at 0 0 270)
			(layer "F.Fab")
			(effects
				(font
					(size 1.27 1.27)
				)
			)
		)
		(duplicate_pad_numbers_are_jumpers no)
		(fp_line
			(start -1.690624 1.074928)
			(end 1.690624 1.074928)
			(stroke
				(width 0.1524)
				(type default)
			)
			(layer "F.SilkS")
		)
		(fp_line
			(start 1.690624 1.074928)
			(end 1.690624 -1.074928)
			(stroke
				(width 0.1524)
				(type default)
			)
			(layer "F.SilkS")
		)
		(fp_line
			(start 0 -0.381)
			(end -0.439928 -1.074928)
			(stroke
				(width 0.1524)
				(type default)
			)
			(layer "F.SilkS")
		)
		(fp_line
			(start -1.690624 -1.074928)
			(end -1.690624 1.074928)
			(stroke
				(width 0.1524)
				(type default)
			)
			(layer "F.SilkS")
		)
		(fp_line
			(start -0.439928 -1.074928)
			(end -1.690624 -1.074928)
			(stroke
				(width 0.1524)
				(type default)
			)
			(layer "F.SilkS")
		)
		(fp_line
			(start 0.439928 -1.074928)
			(end 0 -0.381)
			(stroke
				(width 0.1524)
				(type default)
			)
			(layer "F.SilkS")
		)
		(fp_line
			(start 1.690624 -1.074928)
			(end 0.439928 -1.074928)
			(stroke
				(width 0.1524)
				(type default)
			)
			(layer "F.SilkS")
		)
		(fp_poly
			(pts
				(xy -2.7686 -0.175768) (xy -2.7686 -1.124204) (xy -1.81991 -0.649986)
			)
			(stroke
				(width 0)
				(type default)
			)
			(fill yes)
			(layer "F.SilkS")
		)
		(fp_line
			(start -0.700024 1.074928)
			(end -0.700024 -1.074928)
			(stroke
				(width 0.1)
				(type default)
			)
			(layer "F.Fab")
		)
		(fp_line
			(start 0.700024 1.074928)
			(end -0.700024 1.074928)
			(stroke
				(width 0.1)
				(type default)
			)
			(layer "F.Fab")
		)
		(fp_line
			(start -0.700024 -1.074928)
			(end 0.700024 -1.074928)
			(stroke
				(width 0.1)
				(type default)
			)
			(layer "F.Fab")
		)
		(fp_line
			(start 0.700024 -1.074928)
			(end 0.700024 1.074928)
			(stroke
				(width 0.1)
				(type default)
			)
			(layer "F.Fab")
		)
		(fp_poly
			(pts
				(xy -2.7686 -1.124204) (xy -1.81991 -0.649986) (xy -2.7686 -0.175768)
			)
			(stroke
				(width 0)
				(type default)
			)
			(fill yes)
			(layer "F.Fab")
		)
		(pad "1" smd rect
			(at -1.100074 -0.649986)
			(size 0.4064 0.9144)
			(layers "F.Cu" "F.Mask" "F.Paste")
			(net "PWRGD_P12V_MEM_CPU0_R")
		)
		(pad "2" smd rect
			(at -1.100074 0)
			(size 0.4064 0.9144)
			(layers "F.Cu" "F.Mask" "F.Paste")
			(net "GND")
		)
		(pad "3" smd rect
			(at -1.100074 0.649986)
			(size 0.4064 0.9144)
			(layers "F.Cu" "F.Mask" "F.Paste")
			(net "PWRGD_P12V_MEM_CPU1_R")
		)
		(pad "4" smd rect
			(at 1.100074 0.649986)
			(size 0.4064 0.9144)
			(layers "F.Cu" "F.Mask" "F.Paste")
			(net "PWRGD_P12V_MEM")
		)
		(pad "5" smd rect
			(at 1.100074 0)
			(size 0.4064 0.9144)
			(layers "F.Cu" "F.Mask" "F.Paste")
			(net "P1V8_AUX")
		)
		(pad "6" smd rect
			(at 1.100074 -0.649986)
			(size 0.4064 0.9144)
			(layers "F.Cu" "F.Mask" "F.Paste")
			(net "PU_U38_6")
		)
	)
)
